-- pcdb file, Rev:1.0 written by Allegro Design Entry HDL 16.5-S008 (v16-5-13Y) 10/18/2011 on Tue Oct 25 14:30:27 2011
#ISCELL
  mstr_standard drawing *
  *
#ISCELL
  mstr_standard synonym *
  page1_4p
